# T6G (Grand Teton) — schematic netlist excerpt (pin names and nets, part order shuffled) for the footprints in the layout excerpt that follows; sources: Cadence DE-HDL packaged netlist, KiCad conversion of 04192023_DAF0TMB3IC0_F0TG_MB_C_brd_V02_OCP.brd

C514  Q_CAP  1UF 4V 20% X6S  pkg 0201  page 279 : A = P1V8_CPU0_RT0_1A ; B = GND
R575  Q_RES  0 5% EMPTY  pkg 0402LF  page 55 : A = XTAL_CPU1_R_X32K_X2 ; B = XTAL_CPU1_X32K_X2
C6081  Q_CAP  0.1UF 25V 10% X7R  pkg 0402  page 177 : A = P1V2_AUX ; B = GND

(kicad_pcb
	(version 20260206)
	(generator "pcbnew")
	(generator_version "10.0")
	(general
		(thickness 1.6)
		(legacy_teardrops no)
	)
	(paper "A4")
	(title_block
		(title "04192023_DAF0TMB3IC0_F0TG_MB_C_brd_V02_OCP.brd")
		(comment 1 "Grand Teton / footprints 8096-8098 of 8354")
	)
	(layers
		(0 "F.Cu" signal "TOP")
		(4 "In1.Cu" signal "GND")
		(6 "In2.Cu" signal "IN1")
		(8 "In3.Cu" signal "GND1")
		(10 "In4.Cu" signal "IN2")
		(12 "In5.Cu" signal "GND2")
		(14 "In6.Cu" signal "IN3")
		(16 "In7.Cu" signal "GND3")
		(18 "In8.Cu" signal "VCC")
		(20 "In9.Cu" signal "VCC1")
		(22 "In10.Cu" signal "GND4")
		(24 "In11.Cu" signal "IN4")
		(26 "In12.Cu" signal "GND5")
		(28 "In13.Cu" signal "IN5")
		(30 "In14.Cu" signal "GND6")
		(32 "In15.Cu" signal "IN6")
		(34 "In16.Cu" signal "GND7")
		(2 "B.Cu" signal "BOTTOM")
		(9 "F.Adhes" user "F.Adhesive")
		(11 "B.Adhes" user "B.Adhesive")
		(13 "F.Paste" user "Package Geometry/Pastemask Top")
		(15 "B.Paste" user "Package Geometry/Pastemask Bottom")
		(5 "F.SilkS" user "Ref Des/Silkscreen Top")
		(7 "B.SilkS" user "Ref Des/Silkscreen Bottom")
		(1 "F.Mask" user "Board Geometry/Soldermask Top")
		(3 "B.Mask" user "Board Geometry/Soldermask Bottom")
		(17 "Dwgs.User" user "User.Drawings")
		(19 "Cmts.User" user "User.Comments")
		(21 "Eco1.User" user "User.Eco1")
		(23 "Eco2.User" user "User.Eco2")
		(25 "Edge.Cuts" user "Board Geometry/Outline")
		(27 "Margin" user)
		(31 "F.CrtYd" user "Package Geometry/Place Bound Top")
		(29 "B.CrtYd" user "Package Geometry/Place Bound Bottom")
		(35 "F.Fab" user "Ref Des/Assembly Top")
		(33 "B.Fab" user "Ref Des/Assembly Bottom")
	)
	(footprint ""
		(layer "B.Cu")
		(at 153.975054 -313.96305 90)
		(property "Reference" "R575"
			(at 0 0 90)
			(layer "B.SilkS")
			(hide yes)
			(effects
				(font
					(size 1.27 1.27)
				)
				(justify mirror)
			)
		)
		(property "Value" ""
			(at 0 0 90)
			(layer "B.Fab")
			(effects
				(font
					(size 1.27 1.27)
				)
				(justify mirror)
			)
		)
		(duplicate_pad_numbers_are_jumpers no)
		(fp_line
			(start 0.7874 -0.4064)
			(end -0.7874 -0.4064)
			(stroke
				(width 0.1524)
				(type default)
			)
			(layer "B.SilkS")
		)
		(fp_line
			(start -0.7874 -0.4064)
			(end -0.7874 0.4064)
			(stroke
				(width 0.1524)
				(type default)
			)
			(layer "B.SilkS")
		)
		(fp_line
			(start 0.7874 0.4064)
			(end 0.7874 -0.4064)
			(stroke
				(width 0.1524)
				(type default)
			)
			(layer "B.SilkS")
		)
		(fp_line
			(start -0.7874 0.4064)
			(end 0.7874 0.4064)
			(stroke
				(width 0.1524)
				(type default)
			)
			(layer "B.SilkS")
		)
		(fp_line
			(start 0.67945 -0.305054)
			(end 0.12065 -0.305054)
			(stroke
				(width 0.1)
				(type default)
			)
			(layer "B.Fab")
		)
		(fp_line
			(start 0.12065 -0.305054)
			(end 0.12065 -0.2794)
			(stroke
				(width 0.1)
				(type default)
			)
			(layer "B.Fab")
		)
		(fp_line
			(start -0.12065 -0.3048)
			(end -0.67945 -0.3048)
			(stroke
				(width 0.1)
				(type default)
			)
			(layer "B.Fab")
		)
		(fp_line
			(start -0.67945 -0.3048)
			(end -0.67945 0.3048)
			(stroke
				(width 0.1)
				(type default)
			)
			(layer "B.Fab")
		)
		(fp_line
			(start 0.12065 -0.2794)
			(end -0.12065 -0.2794)
			(stroke
				(width 0.1)
				(type default)
			)
			(layer "B.Fab")
		)
		(fp_line
			(start -0.12065 -0.2794)
			(end -0.12065 -0.3048)
			(stroke
				(width 0.1)
				(type default)
			)
			(layer "B.Fab")
		)
		(fp_line
			(start 0.12065 0.2794)
			(end 0.12065 0.3048)
			(stroke
				(width 0.1)
				(type default)
			)
			(layer "B.Fab")
		)
		(fp_line
			(start -0.120396 0.2794)
			(end 0.12065 0.2794)
			(stroke
				(width 0.1)
				(type default)
			)
			(layer "B.Fab")
		)
		(fp_line
			(start 0.67945 0.3048)
			(end 0.67945 -0.305054)
			(stroke
				(width 0.1)
				(type default)
			)
			(layer "B.Fab")
		)
		(fp_line
			(start 0.12065 0.3048)
			(end 0.67945 0.3048)
			(stroke
				(width 0.1)
				(type default)
			)
			(layer "B.Fab")
		)
		(fp_line
			(start -0.120396 0.3048)
			(end -0.120396 0.2794)
			(stroke
				(width 0.1)
				(type default)
			)
			(layer "B.Fab")
		)
		(fp_line
			(start -0.67945 0.3048)
			(end -0.120396 0.3048)
			(stroke
				(width 0.1)
				(type default)
			)
			(layer "B.Fab")
		)
		(pad "1" smd circle
			(at 0.40005 0 270)
			(size 0 0)
			(layers "B.Cu" "B.Mask" "B.Paste")
			(net "XTAL_CPU1_R_X32K_X2")
		)
		(pad "2" smd circle
			(at -0.40005 0 270)
			(size 0 0)
			(layers "B.Cu" "B.Mask" "B.Paste")
			(net "XTAL_CPU1_X32K_X2")
		)
	)
	(footprint ""
		(layer "B.Cu")
		(at 129.305304 -34.670492)
		(property "Reference" "C6081"
			(at 0 0 0)
			(layer "B.SilkS")
			(hide yes)
			(effects
				(font
					(size 1.27 1.27)
				)
				(justify mirror)
			)
		)
		(property "Value" ""
			(at 0 0 0)
			(layer "B.Fab")
			(effects
				(font
					(size 1.27 1.27)
				)
				(justify mirror)
			)
		)
		(duplicate_pad_numbers_are_jumpers no)
		(fp_line
			(start -0.7874 -0.4064)
			(end -0.7874 0.4064)
			(stroke
				(width 0.1524)
				(type default)
			)
			(layer "B.SilkS")
		)
		(fp_line
			(start -0.7874 0.4064)
			(end 0.7874 0.4064)
			(stroke
				(width 0.1524)
				(type default)
			)
			(layer "B.SilkS")
		)
		(fp_line
			(start 0.7874 -0.4064)
			(end -0.7874 -0.4064)
			(stroke
				(width 0.1524)
				(type default)
			)
			(layer "B.SilkS")
		)
		(fp_line
			(start 0.7874 0.4064)
			(end 0.7874 -0.4064)
			(stroke
				(width 0.1524)
				(type default)
			)
			(layer "B.SilkS")
		)
		(fp_line
			(start -0.67945 -0.3048)
			(end -0.67945 0.3048)
			(stroke
				(width 0.1)
				(type default)
			)
			(layer "B.Fab")
		)
		(fp_line
			(start -0.67945 0.3048)
			(end -0.120396 0.3048)
			(stroke
				(width 0.1)
				(type default)
			)
			(layer "B.Fab")
		)
		(fp_line
			(start -0.12065 -0.3048)
			(end -0.67945 -0.3048)
			(stroke
				(width 0.1)
				(type default)
			)
			(layer "B.Fab")
		)
		(fp_line
			(start -0.12065 -0.2794)
			(end -0.12065 -0.3048)
			(stroke
				(width 0.1)
				(type default)
			)
			(layer "B.Fab")
		)
		(fp_line
			(start -0.120396 0.2794)
			(end 0.12065 0.2794)
			(stroke
				(width 0.1)
				(type default)
			)
			(layer "B.Fab")
		)
		(fp_line
			(start -0.120396 0.3048)
			(end -0.120396 0.2794)
			(stroke
				(width 0.1)
				(type default)
			)
			(layer "B.Fab")
		)
		(fp_line
			(start 0.12065 -0.305054)
			(end 0.12065 -0.2794)
			(stroke
				(width 0.1)
				(type default)
			)
			(layer "B.Fab")
		)
		(fp_line
			(start 0.12065 -0.2794)
			(end -0.12065 -0.2794)
			(stroke
				(width 0.1)
				(type default)
			)
			(layer "B.Fab")
		)
		(fp_line
			(start 0.12065 0.2794)
			(end 0.12065 0.3048)
			(stroke
				(width 0.1)
				(type default)
			)
			(layer "B.Fab")
		)
		(fp_line
			(start 0.12065 0.3048)
			(end 0.67945 0.3048)
			(stroke
				(width 0.1)
				(type default)
			)
			(layer "B.Fab")
		)
		(fp_line
			(start 0.67945 -0.305054)
			(end 0.12065 -0.305054)
			(stroke
				(width 0.1)
				(type default)
			)
			(layer "B.Fab")
		)
		(fp_line
			(start 0.67945 0.3048)
			(end 0.67945 -0.305054)
			(stroke
				(width 0.1)
				(type default)
			)
			(layer "B.Fab")
		)
		(pad "1" smd circle
			(at 0.40005 0 180)
			(size 0 0)
			(layers "B.Cu" "B.Mask" "B.Paste")
			(net "P1V2_AUX")
		)
		(pad "2" smd circle
			(at -0.40005 0 180)
			(size 0 0)
			(layers "B.Cu" "B.Mask" "B.Paste")
			(net "GND")
		)
	)
	(footprint ""
		(layer "B.Cu")
		(at 311.91835 -396.393162 -90)
		(property "Reference" "C514"
			(at 0 0 90)
			(layer "B.SilkS")
			(hide yes)
			(effects
				(font
					(size 1.27 1.27)
				)
				(justify mirror)
			)
		)
		(property "Value" ""
			(at 0 0 90)
			(layer "B.Fab")
			(effects
				(font
					(size 1.27 1.27)
				)
				(justify mirror)
			)
		)
		(duplicate_pad_numbers_are_jumpers no)
		(fp_line
			(start -0.299974 0.150114)
			(end 0.299974 0.150114)
			(stroke
				(width 0.1)
				(type default)
			)
			(layer "B.Fab")
		)
		(fp_line
			(start 0.299974 0.150114)
			(end 0.299974 -0.150114)
			(stroke
				(width 0.1)
				(type default)
			)
			(layer "B.Fab")
		)
		(fp_line
			(start -0.299974 -0.150114)
			(end -0.299974 0.150114)
			(stroke
				(width 0.1)
				(type default)
			)
			(layer "B.Fab")
		)
		(fp_line
			(start 0.299974 -0.150114)
			(end -0.299974 -0.150114)
			(stroke
				(width 0.1)
				(type default)
			)
			(layer "B.Fab")
		)
		(pad "1" smd rect
			(at 0.2667 0 90)
			(size 0.3048 0.381)
			(layers "B.Cu" "B.Mask" "B.Paste")
			(net "P1V8_CPU0_RT0_1A")
		)
		(pad "2" smd rect
			(at -0.2667 0 90)
			(size 0.3048 0.381)
			(layers "B.Cu" "B.Mask" "B.Paste")
			(net "GND")
		)
	)
)
